FILE_TYPE = MULTI_PHYS_TABLE;

PART 'NLASB3157DFT2G_SC88'
CLASS = IC 

{========================================================================================}
:CLS_PN            = JEDEC_TYPE     |ALT_SYMBOLS      |DESCRIPTION             ;
{========================================================================================}
 'G223-10187-01'   = 'SOT363_V2'    |'(SOT363_V2)'    |'IC,2:1 MULTIPLEXER,CMOS ANALOG SWITCH,6P,SOT-363'  

END_PART

END.

